(kicad_pcb
	(version 20241229)
	(generator "pcbnew")
	(generator_version "9.0")
	(general
		(thickness 1.711)
		(legacy_teardrops no)
	)
	(paper "A4")
	(title_block
		(title "Antmicro Baseboard for Jetson AGX Thor")
		(date "2026-02-18")
		(rev "1.1.0")
		(company "Antmicro Ltd")
		(comment 1 "www.antmicro.com")
		(comment 9 "footprints 782-785 of 1170")
	)
	(layers
		(0 "F.Cu" signal)
		(4 "In1.Cu" signal)
		(6 "In2.Cu" signal)
		(8 "In3.Cu" signal)
		(10 "In4.Cu" jumper)
		(12 "In5.Cu" signal)
		(14 "In6.Cu" signal)
		(16 "In7.Cu" signal)
		(18 "In8.Cu" signal)
		(2 "B.Cu" signal)
		(9 "F.Adhes" user "F.Adhesive")
		(11 "B.Adhes" user "B.Adhesive")
		(13 "F.Paste" user)
		(15 "B.Paste" user)
		(5 "F.SilkS" user "F.Silkscreen")
		(7 "B.SilkS" user "B.Silkscreen")
		(1 "F.Mask" user)
		(3 "B.Mask" user)
		(17 "Dwgs.User" user "User.Drawings")
		(19 "Cmts.User" user "User.Comments")
		(21 "Eco1.User" user "User.Eco1")
		(23 "Eco2.User" user "User.Eco2")
		(25 "Edge.Cuts" user)
		(27 "Margin" user)
		(31 "F.CrtYd" user "F.Courtyard")
		(29 "B.CrtYd" user "B.Courtyard")
		(35 "F.Fab" user)
		(33 "B.Fab" user)
	)
	(footprint "antmicro-footprints:R_0402_1005Metric"
		(layer "B.Cu")
		(at 223.56 123.4)
		(descr "Resistor SMD 0402")
		(tags "resistor SMD 0402")
		(property "Reference" "R334"
			(at 0.94 -0.6 0)
			(layer "B.SilkS")
			(effects
				(font
					(size 0.7 0.7)
					(thickness 0.15)
				)
				(justify right top mirror)
			)
		)
		(property "Value" "R_10k_0402"
			(at -1.011843 -1.772047 0)
			(layer "B.Fab")
			(effects
				(font
					(size 0.7 0.7)
					(thickness 0.15)
				)
				(justify right top mirror)
			)
		)
		(property "Datasheet" "https://www.bourns.com/docs/product-datasheets/cr.pdf"
			(at 0 0 0)
			(layer "B.Fab")
			(hide yes)
			(effects
				(font
					(size 1.27 1.27)
					(thickness 0.15)
				)
				(justify mirror)
			)
		)
		(property "Description" "SMD Chip Resistor, 10 kohm, ± 1%, 62.5 mW, 0402 [1005 Metric], Thick Film, General Purpose"
			(at 0 0 0)
			(layer "B.Fab")
			(hide yes)
			(effects
				(font
					(size 1.27 1.27)
					(thickness 0.15)
				)
				(justify mirror)
			)
		)
		(property "MPN" "CR0402-FX-1002GLF"
			(at 0 0 180)
			(unlocked yes)
			(layer "B.Fab")
			(hide yes)
			(effects
				(font
					(size 1 1)
					(thickness 0.15)
				)
				(justify mirror)
			)
		)
		(property "Manufacturer" "Bourns"
			(at 0 0 180)
			(unlocked yes)
			(layer "B.Fab")
			(hide yes)
			(effects
				(font
					(size 1 1)
					(thickness 0.15)
				)
				(justify mirror)
			)
		)
		(property "License" "Apache-2.0"
			(at 0 0 180)
			(unlocked yes)
			(layer "B.Fab")
			(hide yes)
			(effects
				(font
					(size 1 1)
					(thickness 0.15)
				)
				(justify mirror)
			)
		)
		(property "Author" "Antmicro"
			(at 0 0 180)
			(unlocked yes)
			(layer "B.Fab")
			(hide yes)
			(effects
				(font
					(size 1 1)
					(thickness 0.15)
				)
				(justify mirror)
			)
		)
		(property "Val" "10k"
			(at 0 0 180)
			(unlocked yes)
			(layer "B.Fab")
			(hide yes)
			(effects
				(font
					(size 1 1)
					(thickness 0.15)
				)
				(justify mirror)
			)
		)
		(property "Tolerance" "1%"
			(at 0 0 180)
			(unlocked yes)
			(layer "B.Fab")
			(hide yes)
			(effects
				(font
					(size 1 1)
					(thickness 0.15)
				)
				(justify mirror)
			)
		)
		(sheetname "/USB Hub/")
		(sheetfile "usb_hub.kicad_sch")
		(attr smd)
		(fp_rect
			(start -0.925 0.47)
			(end 0.925 -0.47)
			(stroke
				(width 0.05)
				(type default)
			)
			(fill no)
			(layer "B.CrtYd")
		)
		(fp_rect
			(start -0.5 0.25)
			(end 0.5 -0.25)
			(stroke
				(width 0.15)
				(type solid)
			)
			(fill no)
			(layer "B.Fab")
		)
		(fp_text user "License: Apache-2.0"
			(at -0.95 -5.169 0)
			(layer "B.Fab")
			(effects
				(font
					(size 0.7 0.7)
					(thickness 0.15)
				)
				(justify right top mirror)
			)
		)
		(fp_text user "Author: Antmicro"
			(at -0.95 -4.169 0)
			(layer "B.Fab")
			(effects
				(font
					(size 0.7 0.7)
					(thickness 0.15)
				)
				(justify right top mirror)
			)
		)
		(fp_text user "${REFERENCE}"
			(at -0.95 -3.168 0)
			(layer "B.Fab")
			(effects
				(font
					(size 0.7 0.7)
					(thickness 0.15)
				)
				(justify right top mirror)
			)
		)
		(pad "1" smd roundrect
			(at -0.48 0)
			(size 0.59 0.64)
			(layers "B.Cu" "B.Mask" "B.Paste")
			(roundrect_rratio 0.25)
			(net 1084 "/USB Hub/DP1_VCONN1")
			(pintype "passive")
		)
		(pad "2" smd roundrect
			(at 0.48 0)
			(size 0.59 0.64)
			(layers "B.Cu" "B.Mask" "B.Paste")
			(roundrect_rratio 0.25)
			(net 1 "GND")
			(pintype "passive")
		)
	)
	(footprint "antmicro-footprints:C_0402_1005Metric"
		(layer "B.Cu")
		(at 110.25 103.5)
		(descr "Capacitor SMD 0402")
		(tags "capacitor SMD 0402")
		(property "Reference" "C182"
			(at -0.95 -0.4 0)
			(layer "B.SilkS")
			(effects
				(font
					(size 0.7 0.7)
					(thickness 0.15)
				)
				(justify left top mirror)
			)
		)
		(property "Value" "C_220n_0402"
			(at -1.022927 -2.155213 0)
			(layer "B.Fab")
			(effects
				(font
					(size 0.7 0.7)
					(thickness 0.15)
				)
				(justify right top mirror)
			)
		)
		(property "Datasheet" "https://www.yageo.com/en/Chart/Download/pdf/CC0402KRX5R6BB224"
			(at 0 0 0)
			(layer "B.Fab")
			(hide yes)
			(effects
				(font
					(size 1.27 1.27)
					(thickness 0.15)
				)
				(justify mirror)
			)
		)
		(property "Description" "SMD Multilayer Ceramic Capacitor, 0.22 µF, 10 V, 0402 [1005 Metric], ± 10%, X5R, CC Series"
			(at 0 0 0)
			(layer "B.Fab")
			(hide yes)
			(effects
				(font
					(size 1.27 1.27)
					(thickness 0.15)
				)
				(justify mirror)
			)
		)
		(property "MPN" "CC0402KRX5R6BB224"
			(at 0 0 0)
			(unlocked yes)
			(layer "B.Fab")
			(hide yes)
			(effects
				(font
					(size 1 1)
					(thickness 0.15)
				)
				(justify mirror)
			)
		)
		(property "Val" "220n"
			(at 0 0 0)
			(unlocked yes)
			(layer "B.Fab")
			(hide yes)
			(effects
				(font
					(size 1 1)
					(thickness 0.15)
				)
				(justify mirror)
			)
		)
		(property "Voltage" "25V"
			(at 0 0 0)
			(unlocked yes)
			(layer "B.Fab")
			(hide yes)
			(effects
				(font
					(size 1 1)
					(thickness 0.15)
				)
				(justify mirror)
			)
		)
		(property "Dielectric" "X7R"
			(at 0 0 0)
			(unlocked yes)
			(layer "B.Fab")
			(hide yes)
			(effects
				(font
					(size 1 1)
					(thickness 0.15)
				)
				(justify mirror)
			)
		)
		(property "Manufacturer" "YAGEO"
			(at 0 0 0)
			(unlocked yes)
			(layer "B.Fab")
			(hide yes)
			(effects
				(font
					(size 1 1)
					(thickness 0.15)
				)
				(justify mirror)
			)
		)
		(property "License" "Apache-2.0"
			(at 0 0 0)
			(unlocked yes)
			(layer "B.Fab")
			(hide yes)
			(effects
				(font
					(size 1 1)
					(thickness 0.15)
				)
				(justify mirror)
			)
		)
		(property "Author" "Antmicro"
			(at 0 0 0)
			(unlocked yes)
			(layer "B.Fab")
			(hide yes)
			(effects
				(font
					(size 1 1)
					(thickness 0.15)
				)
				(justify mirror)
			)
		)
		(property "Public" "False"
			(at 0 0 0)
			(unlocked yes)
			(layer "B.Fab")
			(hide yes)
			(effects
				(font
					(size 1 1)
					(thickness 0.15)
				)
				(justify mirror)
			)
		)
		(sheetname "/M.2/")
		(sheetfile "m2.kicad_sch")
		(attr smd)
		(fp_poly
			(pts
				(xy -0.925 0.47) (xy -0.925 -0.47) (xy 0.925 -0.47) (xy 0.925 0.47)
			)
			(stroke
				(width 0.05)
				(type default)
			)
			(fill no)
			(layer "B.CrtYd")
		)
		(fp_line
			(start -0.494 -0.248)
			(end -0.494 0.25)
			(stroke
				(width 0.15)
				(type solid)
			)
			(layer "B.Fab")
		)
		(fp_line
			(start -0.494 0.25)
			(end 0.504 0.25)
			(stroke
				(width 0.15)
				(type solid)
			)
			(layer "B.Fab")
		)
		(fp_line
			(start 0.504 -0.248)
			(end -0.494 -0.248)
			(stroke
				(width 0.15)
				(type solid)
			)
			(layer "B.Fab")
		)
		(fp_line
			(start 0.504 0.25)
			(end 0.504 -0.248)
			(stroke
				(width 0.15)
				(type solid)
			)
			(layer "B.Fab")
		)
		(fp_text user "License: Apache-2.0"
			(at -0.939 -5.799 0)
			(layer "B.Fab")
			(effects
				(font
					(size 0.7 0.7)
					(thickness 0.15)
				)
				(justify right top mirror)
			)
		)
		(fp_text user "Author: Antmicro"
			(at -0.939 -3.399 0)
			(layer "B.Fab")
			(effects
				(font
					(size 0.7 0.7)
					(thickness 0.15)
				)
				(justify right top mirror)
			)
		)
		(fp_text user "${REFERENCE}"
			(at -0.939 -4.599 0)
			(layer "B.Fab")
			(effects
				(font
					(size 0.7 0.7)
					(thickness 0.15)
				)
				(justify right top mirror)
			)
		)
		(pad "1" smd roundrect
			(at -0.48 0)
			(size 0.59 0.64)
			(layers "B.Cu" "B.Mask" "B.Paste")
			(roundrect_rratio 0.25)
			(net 392 "/M.2/PCIe_{C5x4}.TX1+")
			(pintype "passive")
		)
		(pad "2" smd roundrect
			(at 0.48 0)
			(size 0.59 0.64)
			(layers "B.Cu" "B.Mask" "B.Paste")
			(roundrect_rratio 0.25)
			(net 391 "/M.2/M2_M_PET1_P")
			(pintype "passive")
		)
	)
	(footprint "antmicro-footprints:R_0402_1005Metric"
		(layer "B.Cu")
		(at 170.805 60.71 90)
		(descr "Resistor SMD 0402")
		(tags "resistor SMD 0402")
		(property "Reference" "R84"
			(at -3.09 -0.405 90)
			(layer "B.SilkS")
			(effects
				(font
					(size 0.7 0.7)
					(thickness 0.15)
				)
				(justify right top mirror)
			)
		)
		(property "Value" "R_10k_0402"
			(at -1.011843 -1.772047 90)
			(layer "B.Fab")
			(effects
				(font
					(size 0.7 0.7)
					(thickness 0.15)
				)
				(justify right top mirror)
			)
		)
		(property "Datasheet" "https://www.bourns.com/docs/product-datasheets/cr.pdf"
			(at 0 0 90)
			(layer "B.Fab")
			(hide yes)
			(effects
				(font
					(size 1.27 1.27)
					(thickness 0.15)
				)
				(justify mirror)
			)
		)
		(property "Description" "SMD Chip Resistor, 10 kohm, ± 1%, 62.5 mW, 0402 [1005 Metric], Thick Film, General Purpose"
			(at 0 0 90)
			(layer "B.Fab")
			(hide yes)
			(effects
				(font
					(size 1.27 1.27)
					(thickness 0.15)
				)
				(justify mirror)
			)
		)
		(property "MPN" "CR0402-FX-1002GLF"
			(at 0 0 270)
			(unlocked yes)
			(layer "B.Fab")
			(hide yes)
			(effects
				(font
					(size 1 1)
					(thickness 0.15)
				)
				(justify mirror)
			)
		)
		(property "Manufacturer" "Bourns"
			(at 0 0 270)
			(unlocked yes)
			(layer "B.Fab")
			(hide yes)
			(effects
				(font
					(size 1 1)
					(thickness 0.15)
				)
				(justify mirror)
			)
		)
		(property "License" "Apache-2.0"
			(at 0 0 270)
			(unlocked yes)
			(layer "B.Fab")
			(hide yes)
			(effects
				(font
					(size 1 1)
					(thickness 0.15)
				)
				(justify mirror)
			)
		)
		(property "Author" "Antmicro"
			(at 0 0 270)
			(unlocked yes)
			(layer "B.Fab")
			(hide yes)
			(effects
				(font
					(size 1 1)
					(thickness 0.15)
				)
				(justify mirror)
			)
		)
		(property "Val" "10k"
			(at 0 0 270)
			(unlocked yes)
			(layer "B.Fab")
			(hide yes)
			(effects
				(font
					(size 1 1)
					(thickness 0.15)
				)
				(justify mirror)
			)
		)
		(property "Tolerance" "1%"
			(at 0 0 270)
			(unlocked yes)
			(layer "B.Fab")
			(hide yes)
			(effects
				(font
					(size 1 1)
					(thickness 0.15)
				)
				(justify mirror)
			)
		)
		(sheetname "/Power/")
		(sheetfile "power.kicad_sch")
		(attr smd)
		(fp_rect
			(start -0.925 0.47)
			(end 0.925 -0.47)
			(stroke
				(width 0.05)
				(type default)
			)
			(fill no)
			(layer "B.CrtYd")
		)
		(fp_rect
			(start -0.5 0.25)
			(end 0.5 -0.25)
			(stroke
				(width 0.15)
				(type solid)
			)
			(fill no)
			(layer "B.Fab")
		)
		(fp_text user "Author: Antmicro"
			(at -0.95 -4.169 90)
			(layer "B.Fab")
			(effects
				(font
					(size 0.7 0.7)
					(thickness 0.15)
				)
				(justify right top mirror)
			)
		)
		(fp_text user "${REFERENCE}"
			(at -0.95 -3.168 90)
			(layer "B.Fab")
			(effects
				(font
					(size 0.7 0.7)
					(thickness 0.15)
				)
				(justify right top mirror)
			)
		)
		(fp_text user "License: Apache-2.0"
			(at -0.95 -5.169 90)
			(layer "B.Fab")
			(effects
				(font
					(size 0.7 0.7)
					(thickness 0.15)
				)
				(justify right top mirror)
			)
		)
		(pad "1" smd roundrect
			(at -0.48 0 90)
			(size 0.59 0.64)
			(layers "B.Cu" "B.Mask" "B.Paste")
			(roundrect_rratio 0.25)
			(net 1 "GND")
			(pintype "passive")
		)
		(pad "2" smd roundrect
			(at 0.48 0 90)
			(size 0.59 0.64)
			(layers "B.Cu" "B.Mask" "B.Paste")
			(roundrect_rratio 0.25)
			(net 11 "+1V8")
			(pintype "passive")
		)
	)
	(footprint "antmicro-footprints:R_0402_1005Metric"
		(layer "B.Cu")
		(at 188.9 121.7 90)
		(descr "Resistor SMD 0402")
		(tags "resistor SMD 0402")
		(property "Reference" "R385"
			(at -3.7 -0.4 90)
			(layer "B.SilkS")
			(effects
				(font
					(size 0.7 0.7)
					(thickness 0.15)
				)
				(justify right top mirror)
			)
		)
		(property "Value" "R_0R_0402"
			(at -1.011843 -1.772047 90)
			(layer "B.Fab")
			(effects
				(font
					(size 0.7 0.7)
					(thickness 0.15)
				)
				(justify right top mirror)
			)
		)
		(property "Datasheet" "https://industrial.panasonic.com/cdbs/www-data/pdf/RDA0000/AOA0000C301.pdf"
			(at 0 0 90)
			(layer "B.Fab")
			(hide yes)
			(effects
				(font
					(size 1.27 1.27)
					(thickness 0.15)
				)
				(justify mirror)
			)
		)
		(property "Description" "SMD Chip Resistor, Jumper, 0 ohm, 100 mW, 0402 [1005 Metric], Thick Film, General Purpose"
			(at 0 0 90)
			(layer "B.Fab")
			(hide yes)
			(effects
				(font
					(size 1.27 1.27)
					(thickness 0.15)
				)
				(justify mirror)
			)
		)
		(property "MPN" "ERJ2GE0R00X"
			(at 0 0 270)
			(unlocked yes)
			(layer "B.Fab")
			(hide yes)
			(effects
				(font
					(size 1 1)
					(thickness 0.15)
				)
				(justify mirror)
			)
		)
		(property "Manufacturer" "Panasonic"
			(at 0 0 270)
			(unlocked yes)
			(layer "B.Fab")
			(hide yes)
			(effects
				(font
					(size 1 1)
					(thickness 0.15)
				)
				(justify mirror)
			)
		)
		(property "License" "Apache-2.0"
			(at 0 0 270)
			(unlocked yes)
			(layer "B.Fab")
			(hide yes)
			(effects
				(font
					(size 1 1)
					(thickness 0.15)
				)
				(justify mirror)
			)
		)
		(property "Author" "Antmicro"
			(at 0 0 270)
			(unlocked yes)
			(layer "B.Fab")
			(hide yes)
			(effects
				(font
					(size 1 1)
					(thickness 0.15)
				)
				(justify mirror)
			)
		)
		(property "Val" "0R"
			(at 0 0 270)
			(unlocked yes)
			(layer "B.Fab")
			(hide yes)
			(effects
				(font
					(size 1 1)
					(thickness 0.15)
				)
				(justify mirror)
			)
		)
		(property "Tolerance" "~"
			(at 0 0 270)
			(unlocked yes)
			(layer "B.Fab")
			(hide yes)
			(effects
				(font
					(size 1 1)
					(thickness 0.15)
				)
				(justify mirror)
			)
		)
		(property "Current" "1A"
			(at 0 0 270)
			(unlocked yes)
			(layer "B.Fab")
			(hide yes)
			(effects
				(font
					(size 1 1)
					(thickness 0.15)
				)
				(justify mirror)
			)
		)
		(sheetname "/USB Debug, PD/")
		(sheetfile "usb_debug_pd.kicad_sch")
		(attr smd exclude_from_pos_files exclude_from_bom dnp)
		(fp_rect
			(start -0.925 0.47)
			(end 0.925 -0.47)
			(stroke
				(width 0.05)
				(type default)
			)
			(fill no)
			(layer "B.CrtYd")
		)
		(fp_rect
			(start -0.5 0.25)
			(end 0.5 -0.25)
			(stroke
				(width 0.15)
				(type solid)
			)
			(fill no)
			(layer "B.Fab")
		)
		(fp_text user "Author: Antmicro"
			(at -0.95 -4.169 90)
			(layer "B.Fab")
			(effects
				(font
					(size 0.7 0.7)
					(thickness 0.15)
				)
				(justify right top mirror)
			)
		)
		(fp_text user "${REFERENCE}"
			(at -0.95 -3.168 90)
			(layer "B.Fab")
			(effects
				(font
					(size 0.7 0.7)
					(thickness 0.15)
				)
				(justify right top mirror)
			)
		)
		(fp_text user "License: Apache-2.0"
			(at -0.95 -5.169 90)
			(layer "B.Fab")
			(effects
				(font
					(size 0.7 0.7)
					(thickness 0.15)
				)
				(justify right top mirror)
			)
		)
		(pad "1" smd roundrect
			(at -0.48 0 90)
			(size 0.59 0.64)
			(layers "B.Cu" "B.Mask" "B.Paste")
			(roundrect_rratio 0.25)
			(net 532 "/USB Debug, PD/SCK")
			(pintype "passive")
		)
		(pad "2" smd roundrect
			(at 0.48 0 90)
			(size 0.59 0.64)
			(layers "B.Cu" "B.Mask" "B.Paste")
			(roundrect_rratio 0.25)
			(net 928 "/USB Debug, PD/SPI_{HUB_DEBUG}.SCK")
			(pintype "passive")
		)
	)
)
